5
5
4
4
3
3
2
2
1
1
D D
C C
B B
A A
RISER_CARD 
Honey Badger 
Title 
Size Document Number Rev 
Date: Sheet o f 
RISER_CARD SA
COVER_PAGE
A
1 3Tuesday, January 20, 2015
Wiwynn Incorporated
http://www.wiwynn.com
8F, 90, Sec.1, Xintai 5th Rd., Xizhi Dist.,
New Taipei City 22102, Taiwan (R.O.C.)
Title 
Size Document Number Rev 
Date: Sheet o f 
RISER_CARD SA
COVER_PAGE
A
1 3Tuesday, January 20, 2015
Wiwynn Incorporated
http://www.wiwynn.com
8F, 90, Sec.1, Xintai 5th Rd., Xizhi Dist.,
New Taipei City 22102, Taiwan (R.O.C.)
Title 
Size Document Number Rev 
Date: Sheet o f 
RISER_CARD SA
COVER_PAGE
A
1 3Tuesday, January 20, 2015
Wiwynn Incorporated
http://www.wiwynn.com
8F, 90, Sec.1, Xintai 5th Rd., Xizhi Dist.,
New Taipei City 22102, Taiwan (R.O.C.)



5
5
4
4
3
3
2
2
1
1
D D
C C
B B
A A
PCIE-connector 
GOLD FINGER 
PCIe2  x8  (Storage) 
SerDes(1GbE) x1 
USB x1 
SATA2 x1 
PCIe2  x4  (10G Ethernet) 
UART(Serial Tx/Rx) 
Title 
Size Document Number Rev 
Date: Sheet o f 
RISER_CARD SA
System BLOCK DIAGRAM
A
2 3Tuesday, January 20, 2015
Wiwynn Incorporated
http://www.wiwynn.com
8F, 90, Sec.1, Xintai 5th Rd., Xizhi Dist.,
New Taipei City 22102, Taiwan (R.O.C.)
Title 
Size Document Number Rev 
Date: Sheet o f 
RISER_CARD SA
System BLOCK DIAGRAM
A
2 3Tuesday, January 20, 2015
Wiwynn Incorporated
http://www.wiwynn.com
8F, 90, Sec.1, Xintai 5th Rd., Xizhi Dist.,
New Taipei City 22102, Taiwan (R.O.C.)
Title 
Size Document Number Rev 
Date: Sheet o f 
RISER_CARD SA
System BLOCK DIAGRAM
A
2 3Tuesday, January 20, 2015
Wiwynn Incorporated
http://www.wiwynn.com
8F, 90, Sec.1, Xintai 5th Rd., Xizhi Dist.,
New Taipei City 22102, Taiwan (R.O.C.)



5
5
4
4
3
3
2
2
1
1
D D
C C
B B
A A
BMC_I2C_DATA
BMC_I2C_CLK
BMC_SYS_RESET#
PMU_PWRBTN#
USB_P1_DN
USB_P1_DP
BMC_I2C_ALERT#
P2E_CPU_SAS_TX_DN0
P2E_CPU_SAS_TX_DP0
P2E_CPU_SAS_TX_DP1
P2E_CPU_SAS_TX_DN1
P2E_CPU_SAS_TX_DP2
P2E_CPU_SAS_TX_DN2
P2E_CPU_SAS_TX_DP3
P2E_CPU_SAS_TX_DN3
SATA2_TX_C_DN0
SATA2_TX_C_DP0
CLK_100M_CLKBUFF_ENET_DN
CLK_100M_CLKBUFF_ENET_DP
PCIE_RSVD_B40
PCIE1_RESET#
GBE_SMBCLK_R
GBE_SMDATA_R
CPU_GBE_TX_C_DP0
CPU_GBE_TX_C_DN0
P2E_CPU_SAS_TX_DN4
P2E_CPU_SAS_TX_DP4
P2E_CPU_SAS_TX_DN5
P2E_CPU_SAS_TX_DP5
P2E_CPU_SAS_TX_DN6
P2E_CPU_SAS_TX_DP6
P2E_CPU_SAS_TX_DN7
P2E_CPU_SAS_TX_DP7
P2E_CPU_ETH10G_TX_DN8
P2E_CPU_ETH10G_TX_DP8
P2E_CPU_ETH10G_TX_DN9
P2E_CPU_ETH10G_TX_DP9
P2E_CPU_ETH10G_TX_DN10
P2E_CPU_ETH10G_TX_DP10
P2E_CPU_ETH10G_TX_DN11
P2E_CPU_ETH10G_TX_DP11
BMC_SYS_RESET#
CLK_100M_PCIE_SAS_C_P
CLK_100M_PCIE_SAS_C_N
CPU_GBE_RX_C_DN0
CPU_GBE_RX_C_DP0
CPU_GBE_TX_C_DP0
PCIE_RSVD_A41
GBE_SMBALRT_R#
GBE_SMBCLK_R
GBE_SMDATA_R
CPU_GBE_TX_C_DN0
SATA2_TX_C_DN0
SATA2_RX_C_DP0
SATA2_RX_C_DN0
SATA2_TX_C_DP0
P2E_CPU_ETH10G_TX_DN8
P2E_CPU_ETH10G_TX_DP8
P2E_CPU_ETH10G_TX_DN9
P2E_CPU_ETH10G_TX_DP9
P2E_CPU_ETH10G_TX_DN10
P2E_CPU_ETH10G_TX_DP10
P2E_CPU_ETH10G_TX_DN11
P2E_CPU_ETH10G_TX_DP11
P2E_CPU_SAS_TX_DP1
P2E_CPU_SAS_TX_DN1
P2E_CPU_SAS_TX_DP2
P2E_CPU_SAS_TX_DN2
P2E_CPU_SAS_TX_DP3
P2E_CPU_SAS_TX_DN3
P2E_CPU_SAS_TX_DN0
P2E_CPU_SAS_TX_DP0
BMC_I2C_ALERT#
P2E_CPU_SAS_RX_DN3
P2E_CPU_SAS_RX_DP3
P2E_CPU_SAS_RX_DP0
P2E_CPU_SAS_RX_DN0
P2E_CPU_SAS_RX_DN1
P2E_CPU_SAS_RX_DP1
P2E_CPU_SAS_RX_DN2
P2E_CPU_SAS_RX_DP2
P2E_CPU_ETH10G_RX_DN10
P2E_CPU_ETH10G_RX_DP10
P2E_CPU_ETH10G_RX_DN11
P2E_CPU_ETH10G_RX_DP11
P2E_CPU_ETH10G_RX_DN8
P2E_CPU_ETH10G_RX_DN9
P2E_CPU_ETH10G_RX_DP8
P2E_CPU_ETH10G_RX_DP9
PMU_PWRBTN#
BOARD_PRSNT#
PCIE_RESET#
SLOT_ID1
PCIE_RSVD_B40
USB_P1_DN
USB_P1_DP
BMC_I2C_DATA
P2E_CPU_SAS_TX_DN5
P2E_CPU_SAS_TX_DP5
P2E_CPU_SAS_TX_DN6
P2E_CPU_SAS_TX_DP6
P2E_CPU_SAS_TX_DN7
P2E_CPU_SAS_TX_DP7
P2E_CPU_SAS_TX_DN4
P2E_CPU_SAS_TX_DP4
P2E_CPU_SAS_RX_DP4
P2E_CPU_SAS_RX_DN4
P2E_CPU_SAS_RX_DP5
P2E_CPU_SAS_RX_DN5
P2E_CPU_SAS_RX_DP6
P2E_CPU_SAS_RX_DN6
P2E_CPU_SAS_RX_DN7
P2E_CPU_SAS_RX_DP7
SLOT_ID2
SLOT_ID3
CLK_100M_CLKBUFF_ENET_DP
CLK_100M_CLKBUFF_ENET_DN
BMC_I2C_CLK
PCIE_RSVD_A37
PCIE_RSVD_A38
PCIE1_RESET#
CPU_TXD
SLOT_ID0
CPU_RXD
BOARD_PRSNT#
PCIE_RESET#
SLOT_ID1
SLOT_ID2
SLOT_ID3
CPU_TXD
SLOT_ID0
CPU_RXD
CLK_100M_PCIE_SAS_C_P
CLK_100M_PCIE_SAS_C_N
P2E_CPU_SAS_RX_DP0
P2E_CPU_SAS_RX_DN0
P2E_CPU_SAS_RX_DN1
P2E_CPU_SAS_RX_DP1
P2E_CPU_SAS_RX_DN2
P2E_CPU_SAS_RX_DP2
P2E_CPU_SAS_RX_DN3
P2E_CPU_SAS_RX_DP3
SATA2_RX_C_DP0
SATA2_RX_C_DN0
PCIE_RSVD_A37
PCIE_RSVD_A38
PCIE_RSVD_A41
GBE_SMBALRT_R#
CPU_GBE_RX_C_DN0
CPU_GBE_RX_C_DP0
P2E_CPU_SAS_RX_DP4
P2E_CPU_SAS_RX_DN4
P2E_CPU_SAS_RX_DP5
P2E_CPU_SAS_RX_DN5
P2E_CPU_SAS_RX_DP6
P2E_CPU_SAS_RX_DN6
P2E_CPU_SAS_RX_DN7
P2E_CPU_SAS_RX_DP7
P2E_CPU_ETH10G_RX_DN8
P2E_CPU_ETH10G_RX_DP8
P2E_CPU_ETH10G_RX_DN9
P2E_CPU_ETH10G_RX_DP9
P2E_CPU_ETH10G_RX_DN10
P2E_CPU_ETH10G_RX_DN11
P2E_CPU_ETH10G_RX_DP11
P2E_CPU_ETH10G_RX_DP10
P12V
P12V
P12V
P12V
P12V
P12V
Title 
Size Document Number R e v 
Date: Sheet 
o f 
RISER_CARD SA
CONNECTOR_GOLD FINGER
A3
3 3Tuesday, January 20, 2015
Wiwynn Incorporated
http://www.wiwynn.com
8F, 90, Sec.1, Xintai 5th Rd., Xizhi Dist.,
New Taipei City 22102, Taiwan (R.O.C.)
Title 
Size Document Number R e v 
Date: Sheet 
o f 
RISER_CARD SA
CONNECTOR_GOLD FINGER
A3
3 3Tuesday, January 20, 2015
Wiwynn Incorporated
http://www.wiwynn.com
8F, 90, Sec.1, Xintai 5th Rd., Xizhi Dist.,
New Taipei City 22102, Taiwan (R.O.C.)
Title 
Size Document Number R e v 
Date: Sheet 
o f 
RISER_CARD SA
CONNECTOR_GOLD FINGER
A3
3 3Tuesday, January 20, 2015
Wiwynn Incorporated
http://www.wiwynn.com
8F, 90, Sec.1, Xintai 5th Rd., Xizhi Dist.,
New Taipei City 22102, Taiwan (R.O.C.)
02 Do not mirror 
TOP BOTTOM 
GF2
GF-PCIE-164P-4-GP
A1 A1
A2 A2
A3 A3
A4 A4
A5 A5
A6 A6
A7 A7
A8 A8
A9 A9
A10 A10
A11 A11
A12 A12
A13 A13
A14 A14
A15 A15
A16 A16
A17 A17
A18 A18
A19 A19
A20 A20
A21 A21
A22 A22
A23 A23
A24 A24
A25 A25
A26 A26
A27 A27
A28 A28
A29 A29
A30 A30
A31 A31
A32 A32
A33 A33
A34 A34
A35 A35
A36 A36
A37 A37
A38 A38
A39 A39
A40 A40
A41 A41
A42 A42
A43 A43
A44 A44
A45 A45
A46 A46
A47 A47
A48 A48
A49 A49
A50 A50
A51 A51
A52 A52
A53 A53
A54 A54
A55 A55
A56 A56
A57 A57
A58 A58
A59 A59
A60 A60
A61 A61
A62 A62
A63 A63
A64 A64
A65 A65
A66 A66
A67 A67
A68 A68
A69 A69
A70 A70
A71 A71
A72 A72
A73 A73
A74 A74
A75 A75
A76 A76
A77 A77
A78 A78
A79 A79
A80 A80
A81 A81
A82 A82
B1B1
B2B2
B3B3
B4B4
B5B5
B6B6
B7B7
B8B8
B9B9
B10B10
B11B11
B12B12
B13B13
B14B14
B15B15
B16B16
B17B17
B18B18
B19B19
B20B20
B21B21
B22B22
B23B23
B24B24
B25B25
B26B26
B27B27
B28B28
B29B29
B30B30
B31B31
B32B32
B33B33
B34B34
B35B35
B36B36
B37B37
B38B38
B39B39
B40B40
B41B41
B42B42
B43B43
B44B44
B45B45
B46B46
B47B47
B48B48
B49B49
B50B50
B51B51
B52B52
B53B53
B54B54
B55B55
B56B56
B57B57
B58B58
B59B59
B60B60
B61B61
B62B62
B63B63
B64B64
B65B65
B66B66
B67B67
B68B68
B69B69
B70B70
B71B71
B72B72
B73B73
B74B74
B75B75
B76B76
B77B77
B78B78
B79B79
B80B80
B81B81
B82B82
CN1
PCISLT164-44-GP
A1
A2
A3
A4
A5
A6
A7
A8
A9
A10
A11
A12
A13
A14
A15
A16
A17
A18
A19
A20
A21
A22
A23
A24
A25
A26
A27
A28
A29
A30
A31
A32
A33
A34
A35
A36
A37
A38
A39
A40
A41
A42
A43
A44
A45
A46
A47
A48
A49
A50
A51
A52
A53
A54
A55
A56
A57
A58
A59
A60
A61
A62
A63
A64
A65
A66
A67
A68
A69
A70
A71
A72
A73
A74
A75
A76
A77
A78
A79
A80
A81
A82
B1
B2
B3
B4
B5
B6
B7
B8
B9
B10
B11
B12
B13
B14
B15
B16
B17
B18
B19
B20
B21
B22
B23
B24
B25
B26
B27
B28
B29
B30
B31
B32
B33
B34
B35
B36
B37
B38
B39
B40
B41
B42
B43
B44
B45
B46
B47
B48
B49
B50
B51
B52
B53
B54
B55
B56
B57
B58
B59
B60
B61
B62
B63
B64
B65
B66
B67
B68
B69
B70
B71
B72
B73
B74
B75
B76
B77
B78
B79
B80
B81
B82
NP1
NP2